(kicad_pcb
	(version 20260206)
	(generator "pcbnew")
	(generator_version "10.0")
	(general
		(thickness 1.6)
		(legacy_teardrops no)
	)
	(paper "A4")
	(title_block
		(title "04192023_DAF0TMB3IC0_F0TG_MB_C_brd_V02_OCP.brd")
		(comment 1 "Grand Teton / footprints 6096-6102 of 8354")
	)
	(layers
		(0 "F.Cu" signal "TOP")
		(4 "In1.Cu" signal "GND")
		(6 "In2.Cu" signal "IN1")
		(8 "In3.Cu" signal "GND1")
		(10 "In4.Cu" signal "IN2")
		(12 "In5.Cu" signal "GND2")
		(14 "In6.Cu" signal "IN3")
		(16 "In7.Cu" signal "GND3")
		(18 "In8.Cu" signal "VCC")
		(20 "In9.Cu" signal "VCC1")
		(22 "In10.Cu" signal "GND4")
		(24 "In11.Cu" signal "IN4")
		(26 "In12.Cu" signal "GND5")
		(28 "In13.Cu" signal "IN5")
		(30 "In14.Cu" signal "GND6")
		(32 "In15.Cu" signal "IN6")
		(34 "In16.Cu" signal "GND7")
		(2 "B.Cu" signal "BOTTOM")
		(9 "F.Adhes" user "F.Adhesive")
		(11 "B.Adhes" user "B.Adhesive")
		(13 "F.Paste" user "Package Geometry/Pastemask Top")
		(15 "B.Paste" user "Package Geometry/Pastemask Bottom")
		(5 "F.SilkS" user "Ref Des/Silkscreen Top")
		(7 "B.SilkS" user "Ref Des/Silkscreen Bottom")
		(1 "F.Mask" user "Board Geometry/Soldermask Top")
		(3 "B.Mask" user "Board Geometry/Soldermask Bottom")
		(17 "Dwgs.User" user "User.Drawings")
		(19 "Cmts.User" user "User.Comments")
		(21 "Eco1.User" user "User.Eco1")
		(23 "Eco2.User" user "User.Eco2")
		(25 "Edge.Cuts" user "Board Geometry/Outline")
		(27 "Margin" user)
		(31 "F.CrtYd" user "Package Geometry/Place Bound Top")
		(29 "B.CrtYd" user "Package Geometry/Place Bound Bottom")
		(35 "F.Fab" user "Ref Des/Assembly Top")
		(33 "B.Fab" user "Ref Des/Assembly Bottom")
	)
	(footprint ""
		(layer "B.Cu")
		(at 308.49697 -389.49503 180)
		(property "Reference" "C7008"
			(at -1.7399 -2.910332 0)
			(unlocked yes)
			(layer "B.SilkS")
			(effects
				(font
					(size 0.7874 0.5842)
					(thickness 0.1524)
				)
				(justify left mirror)
			)
		)
		(property "Value" ""
			(at 0 0 0)
			(layer "B.Fab")
			(effects
				(font
					(size 1.27 1.27)
				)
				(justify mirror)
			)
		)
		(duplicate_pad_numbers_are_jumpers no)
		(fp_line
			(start 4.84378 -2.150618)
			(end 4.842256 2.163064)
			(stroke
				(width 0.1524)
				(type default)
			)
			(layer "B.SilkS")
		)
		(fp_line
			(start 4.84378 -2.150618)
			(end 4.53898 -2.150618)
			(stroke
				(width 0.1524)
				(type default)
			)
			(layer "B.SilkS")
		)
		(fp_line
			(start 4.83108 2.150364)
			(end 4.447794 2.149348)
			(stroke
				(width 0.1524)
				(type default)
			)
			(layer "B.SilkS")
		)
		(fp_line
			(start 4.69138 -2.150618)
			(end 4.692396 2.161032)
			(stroke
				(width 0.1524)
				(type default)
			)
			(layer "B.SilkS")
		)
		(fp_line
			(start 4.53898 2.15011)
			(end 4.53898 -2.15011)
			(stroke
				(width 0.1524)
				(type default)
			)
			(layer "B.SilkS")
		)
		(fp_line
			(start 4.53898 -2.15011)
			(end -4.53898 -2.15011)
			(stroke
				(width 0.1524)
				(type default)
			)
			(layer "B.SilkS")
		)
		(fp_line
			(start 4.53898 -2.150618)
			(end 4.539742 2.152142)
			(stroke
				(width 0.1524)
				(type default)
			)
			(layer "B.SilkS")
		)
		(fp_line
			(start -4.53898 2.15011)
			(end 4.53898 2.15011)
			(stroke
				(width 0.1524)
				(type default)
			)
			(layer "B.SilkS")
		)
		(fp_line
			(start -4.53898 -2.15011)
			(end -4.53898 2.15011)
			(stroke
				(width 0.1524)
				(type default)
			)
			(layer "B.SilkS")
		)
		(fp_line
			(start 3.64998 2.15011)
			(end 3.64998 -2.15011)
			(stroke
				(width 0.1)
				(type default)
			)
			(layer "B.Fab")
		)
		(fp_line
			(start 3.64998 -2.15011)
			(end -3.64998 -2.15011)
			(stroke
				(width 0.1)
				(type default)
			)
			(layer "B.Fab")
		)
		(fp_line
			(start -3.64998 2.15011)
			(end 3.64998 2.15011)
			(stroke
				(width 0.1)
				(type default)
			)
			(layer "B.Fab")
		)
		(fp_line
			(start -3.64998 -2.15011)
			(end -3.64998 2.15011)
			(stroke
				(width 0.1)
				(type default)
			)
			(layer "B.Fab")
		)
		(fp_text user "+"
			(at 4.327652 -3.143758 180)
			(unlocked yes)
			(layer "B.SilkS")
			(effects
				(font
					(size 1.905 1.4224)
					(thickness 0.1524)
				)
				(justify left mirror)
			)
		)
		(fp_text user "-"
			(at -2.969514 -2.667508 180)
			(unlocked yes)
			(layer "B.SilkS")
			(effects
				(font
					(size 1.905 1.4224)
					(thickness 0.1524)
				)
				(justify left mirror)
			)
		)
		(fp_text user "+"
			(at 6.214872 -0.337058 180)
			(unlocked yes)
			(layer "B.Fab")
			(effects
				(font
					(size 1.905 1.4224)
					(thickness 0.1524)
				)
				(justify left mirror)
			)
		)
		(fp_text user "-"
			(at -4.313174 -0.094488 180)
			(unlocked yes)
			(layer "B.Fab")
			(effects
				(font
					(size 1.905 1.4224)
					(thickness 0.1524)
				)
				(justify left mirror)
			)
		)
		(pad "1" smd rect
			(at 3.199892 0)
			(size 2.413 2.8194)
			(layers "B.Cu" "B.Mask" "B.Paste")
			(net "P0V9_CPU0_RT0_2A")
		)
		(pad "2" smd rect
			(at -3.199892 0)
			(size 2.413 2.8194)
			(layers "B.Cu" "B.Mask" "B.Paste")
			(net "GND")
		)
	)
	(footprint ""
		(layer "B.Cu")
		(at 183.896 -20.378166 90)
		(property "Reference" "R3238"
			(at 0 0 90)
			(layer "B.SilkS")
			(hide yes)
			(effects
				(font
					(size 1.27 1.27)
				)
				(justify mirror)
			)
		)
		(property "Value" ""
			(at 0 0 90)
			(layer "B.Fab")
			(effects
				(font
					(size 1.27 1.27)
				)
				(justify mirror)
			)
		)
		(duplicate_pad_numbers_are_jumpers no)
		(fp_line
			(start 0.7874 -0.4064)
			(end -0.7874 -0.4064)
			(stroke
				(width 0.1524)
				(type default)
			)
			(layer "B.SilkS")
		)
		(fp_line
			(start -0.7874 -0.4064)
			(end -0.7874 0.4064)
			(stroke
				(width 0.1524)
				(type default)
			)
			(layer "B.SilkS")
		)
		(fp_line
			(start 0.7874 0.4064)
			(end 0.7874 -0.4064)
			(stroke
				(width 0.1524)
				(type default)
			)
			(layer "B.SilkS")
		)
		(fp_line
			(start -0.7874 0.4064)
			(end 0.7874 0.4064)
			(stroke
				(width 0.1524)
				(type default)
			)
			(layer "B.SilkS")
		)
		(fp_line
			(start 0.67945 -0.305054)
			(end 0.12065 -0.305054)
			(stroke
				(width 0.1)
				(type default)
			)
			(layer "B.Fab")
		)
		(fp_line
			(start 0.12065 -0.305054)
			(end 0.12065 -0.2794)
			(stroke
				(width 0.1)
				(type default)
			)
			(layer "B.Fab")
		)
		(fp_line
			(start -0.12065 -0.3048)
			(end -0.67945 -0.3048)
			(stroke
				(width 0.1)
				(type default)
			)
			(layer "B.Fab")
		)
		(fp_line
			(start -0.67945 -0.3048)
			(end -0.67945 0.3048)
			(stroke
				(width 0.1)
				(type default)
			)
			(layer "B.Fab")
		)
		(fp_line
			(start 0.12065 -0.2794)
			(end -0.12065 -0.2794)
			(stroke
				(width 0.1)
				(type default)
			)
			(layer "B.Fab")
		)
		(fp_line
			(start -0.12065 -0.2794)
			(end -0.12065 -0.3048)
			(stroke
				(width 0.1)
				(type default)
			)
			(layer "B.Fab")
		)
		(fp_line
			(start 0.12065 0.2794)
			(end 0.12065 0.3048)
			(stroke
				(width 0.1)
				(type default)
			)
			(layer "B.Fab")
		)
		(fp_line
			(start -0.120396 0.2794)
			(end 0.12065 0.2794)
			(stroke
				(width 0.1)
				(type default)
			)
			(layer "B.Fab")
		)
		(fp_line
			(start 0.67945 0.3048)
			(end 0.67945 -0.305054)
			(stroke
				(width 0.1)
				(type default)
			)
			(layer "B.Fab")
		)
		(fp_line
			(start 0.12065 0.3048)
			(end 0.67945 0.3048)
			(stroke
				(width 0.1)
				(type default)
			)
			(layer "B.Fab")
		)
		(fp_line
			(start -0.120396 0.3048)
			(end -0.120396 0.2794)
			(stroke
				(width 0.1)
				(type default)
			)
			(layer "B.Fab")
		)
		(fp_line
			(start -0.67945 0.3048)
			(end -0.120396 0.3048)
			(stroke
				(width 0.1)
				(type default)
			)
			(layer "B.Fab")
		)
		(pad "1" smd circle
			(at 0.40005 0 270)
			(size 0 0)
			(layers "B.Cu" "B.Mask" "B.Paste")
			(net "SMB_OCP_SFF_3V3AUX_SCL")
		)
		(pad "2" smd circle
			(at -0.40005 0 270)
			(size 0 0)
			(layers "B.Cu" "B.Mask" "B.Paste")
			(net "SMB_OCP_SFF_3V3AUX_SCL_R0")
		)
	)
	(footprint ""
		(layer "B.Cu")
		(at 161.94024 -419.262306)
		(property "Reference" "R1214"
			(at 0 0 0)
			(layer "B.SilkS")
			(hide yes)
			(effects
				(font
					(size 1.27 1.27)
				)
				(justify mirror)
			)
		)
		(property "Value" ""
			(at 0 0 0)
			(layer "B.Fab")
			(effects
				(font
					(size 1.27 1.27)
				)
				(justify mirror)
			)
		)
		(duplicate_pad_numbers_are_jumpers no)
		(fp_line
			(start -0.32512 -0.175006)
			(end -0.32512 0.175006)
			(stroke
				(width 0.1)
				(type default)
			)
			(layer "B.Fab")
		)
		(fp_line
			(start -0.32512 0.175006)
			(end 0.32512 0.175006)
			(stroke
				(width 0.1)
				(type default)
			)
			(layer "B.Fab")
		)
		(fp_line
			(start 0.32512 -0.175006)
			(end -0.32512 -0.175006)
			(stroke
				(width 0.1)
				(type default)
			)
			(layer "B.Fab")
		)
		(fp_line
			(start 0.32512 0.175006)
			(end 0.32512 -0.175006)
			(stroke
				(width 0.1)
				(type default)
			)
			(layer "B.Fab")
		)
		(pad "1" smd rect
			(at 0.2667 0 180)
			(size 0.3048 0.381)
			(layers "B.Cu" "B.Mask" "B.Paste")
			(net "GND")
		)
		(pad "2" smd rect
			(at -0.2667 0)
			(size 0.3048 0.381)
			(layers "B.Cu" "B.Mask" "B.Paste")
			(net "RT_ROM_MUX4_OE_N")
		)
	)
	(footprint ""
		(layer "B.Cu")
		(at 5.260086 -35.495484 180)
		(property "Reference" ""
			(at 0 0 0)
			(layer "B.SilkS")
			(hide yes)
			(effects
				(font
					(size 1.27 1.27)
				)
				(justify mirror)
			)
		)
		(property "Value" ""
			(at 0 0 0)
			(layer "B.Fab")
			(effects
				(font
					(size 1.27 1.27)
				)
				(justify mirror)
			)
		)
		(duplicate_pad_numbers_are_jumpers no)
		(pad "1" smd circle
			(at 0 0)
			(size 0.9906 0.9906)
			(layers "B.Cu" "B.Mask" "B.Paste")
			(net "Net_2236")
		)
		(zone
			(layer "B.Cu")
			(hatch none 0.5)
			(connect_pads
				(clearance 0)
			)
			(min_thickness 0.25)
			(keepout
				(tracks not_allowed)
				(vias allowed)
				(pads allowed)
				(copperpour not_allowed)
				(footprints allowed)
			)
			(placement
				(enabled no)
				(sheetname "")
			)
			(fill
				(thermal_gap 0.5)
				(thermal_bridge_width 0.5)
				(island_removal_mode 0)
			)
			(polygon
				(pts
					(arc
						(start 6.885686 -35.495484)
						(mid 3.634486 -35.495484)
						(end 6.885686 -35.495484)
					)
				)
			)
		)
	)
	(footprint ""
		(layer "B.Cu")
		(at 143.969486 -408.517344 90)
		(property "Reference" "C6744"
			(at 0 0 90)
			(layer "B.SilkS")
			(hide yes)
			(effects
				(font
					(size 1.27 1.27)
				)
				(justify mirror)
			)
		)
		(property "Value" ""
			(at 0 0 90)
			(layer "B.Fab")
			(effects
				(font
					(size 1.27 1.27)
				)
				(justify mirror)
			)
		)
		(duplicate_pad_numbers_are_jumpers no)
		(fp_line
			(start 0.299974 -0.150114)
			(end -0.299974 -0.150114)
			(stroke
				(width 0.1)
				(type default)
			)
			(layer "B.Fab")
		)
		(fp_line
			(start -0.299974 -0.150114)
			(end -0.299974 0.150114)
			(stroke
				(width 0.1)
				(type default)
			)
			(layer "B.Fab")
		)
		(fp_line
			(start 0.299974 0.150114)
			(end 0.299974 -0.150114)
			(stroke
				(width 0.1)
				(type default)
			)
			(layer "B.Fab")
		)
		(fp_line
			(start -0.299974 0.150114)
			(end 0.299974 0.150114)
			(stroke
				(width 0.1)
				(type default)
			)
			(layer "B.Fab")
		)
		(pad "1" smd rect
			(at 0.2667 0 270)
			(size 0.3048 0.381)
			(layers "B.Cu" "B.Mask" "B.Paste")
			(net "P5E_CPU1_P3_TX_BUF_C_DN<9>")
		)
		(pad "2" smd rect
			(at -0.2667 0 270)
			(size 0.3048 0.381)
			(layers "B.Cu" "B.Mask" "B.Paste")
			(net "P5E_CPU1_P3_TX_BUF_DN<9>")
		)
	)
	(footprint ""
		(layer "B.Cu")
		(at 365.09579 -393.04468 180)
		(property "Reference" "R1116"
			(at 0 0 0)
			(layer "B.SilkS")
			(hide yes)
			(effects
				(font
					(size 1.27 1.27)
				)
				(justify mirror)
			)
		)
		(property "Value" ""
			(at 0 0 0)
			(layer "B.Fab")
			(effects
				(font
					(size 1.27 1.27)
				)
				(justify mirror)
			)
		)
		(duplicate_pad_numbers_are_jumpers no)
		(fp_line
			(start 0.32512 0.175006)
			(end 0.32512 -0.175006)
			(stroke
				(width 0.1)
				(type default)
			)
			(layer "B.Fab")
		)
		(fp_line
			(start 0.32512 -0.175006)
			(end -0.32512 -0.175006)
			(stroke
				(width 0.1)
				(type default)
			)
			(layer "B.Fab")
		)
		(fp_line
			(start -0.32512 0.175006)
			(end 0.32512 0.175006)
			(stroke
				(width 0.1)
				(type default)
			)
			(layer "B.Fab")
		)
		(fp_line
			(start -0.32512 -0.175006)
			(end -0.32512 0.175006)
			(stroke
				(width 0.1)
				(type default)
			)
			(layer "B.Fab")
		)
		(pad "1" smd rect
			(at 0.2667 0)
			(size 0.3048 0.381)
			(layers "B.Cu" "B.Mask" "B.Paste")
			(net "P1V8_CPU0_RT_1D")
		)
		(pad "2" smd rect
			(at -0.2667 0 180)
			(size 0.3048 0.381)
			(layers "B.Cu" "B.Mask" "B.Paste")
			(net "TEST1_RT_CPU0_P3")
		)
	)
	(footprint ""
		(layer "B.Cu")
		(at 396.546578 -327.766172 180)
		(property "Reference" "R1351"
			(at 0 0 0)
			(layer "B.SilkS")
			(hide yes)
			(effects
				(font
					(size 1.27 1.27)
				)
				(justify mirror)
			)
		)
		(property "Value" ""
			(at 0 0 0)
			(layer "B.Fab")
			(effects
				(font
					(size 1.27 1.27)
				)
				(justify mirror)
			)
		)
		(duplicate_pad_numbers_are_jumpers no)
		(fp_line
			(start 0.7874 0.4064)
			(end 0.7874 -0.4064)
			(stroke
				(width 0.1524)
				(type default)
			)
			(layer "B.SilkS")
		)
		(fp_line
			(start 0.7874 -0.4064)
			(end -0.7874 -0.4064)
			(stroke
				(width 0.1524)
				(type default)
			)
			(layer "B.SilkS")
		)
		(fp_line
			(start -0.7874 0.4064)
			(end 0.7874 0.4064)
			(stroke
				(width 0.1524)
				(type default)
			)
			(layer "B.SilkS")
		)
		(fp_line
			(start -0.7874 -0.4064)
			(end -0.7874 0.4064)
			(stroke
				(width 0.1524)
				(type default)
			)
			(layer "B.SilkS")
		)
		(fp_line
			(start 0.67945 0.3048)
			(end 0.67945 -0.305054)
			(stroke
				(width 0.1)
				(type default)
			)
			(layer "B.Fab")
		)
		(fp_line
			(start 0.67945 -0.305054)
			(end 0.12065 -0.305054)
			(stroke
				(width 0.1)
				(type default)
			)
			(layer "B.Fab")
		)
		(fp_line
			(start 0.12065 0.3048)
			(end 0.67945 0.3048)
			(stroke
				(width 0.1)
				(type default)
			)
			(layer "B.Fab")
		)
		(fp_line
			(start 0.12065 0.2794)
			(end 0.12065 0.3048)
			(stroke
				(width 0.1)
				(type default)
			)
			(layer "B.Fab")
		)
		(fp_line
			(start 0.12065 -0.2794)
			(end -0.12065 -0.2794)
			(stroke
				(width 0.1)
				(type default)
			)
			(layer "B.Fab")
		)
		(fp_line
			(start 0.12065 -0.305054)
			(end 0.12065 -0.2794)
			(stroke
				(width 0.1)
				(type default)
			)
			(layer "B.Fab")
		)
		(fp_line
			(start -0.120396 0.3048)
			(end -0.120396 0.2794)
			(stroke
				(width 0.1)
				(type default)
			)
			(layer "B.Fab")
		)
		(fp_line
			(start -0.120396 0.2794)
			(end 0.12065 0.2794)
			(stroke
				(width 0.1)
				(type default)
			)
			(layer "B.Fab")
		)
		(fp_line
			(start -0.12065 -0.2794)
			(end -0.12065 -0.3048)
			(stroke
				(width 0.1)
				(type default)
			)
			(layer "B.Fab")
		)
		(fp_line
			(start -0.12065 -0.3048)
			(end -0.67945 -0.3048)
			(stroke
				(width 0.1)
				(type default)
			)
			(layer "B.Fab")
		)
		(fp_line
			(start -0.67945 0.3048)
			(end -0.120396 0.3048)
			(stroke
				(width 0.1)
				(type default)
			)
			(layer "B.Fab")
		)
		(fp_line
			(start -0.67945 -0.3048)
			(end -0.67945 0.3048)
			(stroke
				(width 0.1)
				(type default)
			)
			(layer "B.Fab")
		)
		(pad "1" smd circle
			(at 0.40005 0)
			(size 0 0)
			(layers "B.Cu" "B.Mask" "B.Paste")
			(net "RST_CPU0_KBRST_R_N")
		)
		(pad "2" smd circle
			(at -0.40005 0)
			(size 0 0)
			(layers "B.Cu" "B.Mask" "B.Paste")
			(net "PVDD18_S5_P0")
		)
	)
)
